# T6G (Grand Teton) — schematic netlist excerpt (pin names and nets, part order shuffled) for the footprints in the layout excerpt that follows; sources: Cadence DE-HDL packaged netlist, KiCad conversion of 04192023_DAF0TMB3IC0_F0TG_MB_C_brd_V02_OCP.brd

C12  Q_CAP  0.1UF 25V 10% X7R  pkg 0402  page 125 : A = GPU_3V3IO_RSVD0_FFU_ISO ; B = GND
R141  Q_RES  0 5% CHIP  pkg 0402LF  page 82 : A = PVDDCR_CPU1_P1_OCP_N ; B = FM_PVDDCR_CPU1_P1_OCP_N

(kicad_pcb
	(version 20260206)
	(generator "pcbnew")
	(generator_version "10.0")
	(general
		(thickness 1.6)
		(legacy_teardrops no)
	)
	(paper "A4")
	(title_block
		(title "04192023_DAF0TMB3IC0_F0TG_MB_C_brd_V02_OCP.brd")
		(comment 1 "Grand Teton / footprints 7661-7662 of 8354")
	)
	(layers
		(0 "F.Cu" signal "TOP")
		(4 "In1.Cu" signal "GND")
		(6 "In2.Cu" signal "IN1")
		(8 "In3.Cu" signal "GND1")
		(10 "In4.Cu" signal "IN2")
		(12 "In5.Cu" signal "GND2")
		(14 "In6.Cu" signal "IN3")
		(16 "In7.Cu" signal "GND3")
		(18 "In8.Cu" signal "VCC")
		(20 "In9.Cu" signal "VCC1")
		(22 "In10.Cu" signal "GND4")
		(24 "In11.Cu" signal "IN4")
		(26 "In12.Cu" signal "GND5")
		(28 "In13.Cu" signal "IN5")
		(30 "In14.Cu" signal "GND6")
		(32 "In15.Cu" signal "IN6")
		(34 "In16.Cu" signal "GND7")
		(2 "B.Cu" signal "BOTTOM")
		(9 "F.Adhes" user "F.Adhesive")
		(11 "B.Adhes" user "B.Adhesive")
		(13 "F.Paste" user "Package Geometry/Pastemask Top")
		(15 "B.Paste" user "Package Geometry/Pastemask Bottom")
		(5 "F.SilkS" user "Ref Des/Silkscreen Top")
		(7 "B.SilkS" user "Ref Des/Silkscreen Bottom")
		(1 "F.Mask" user "Board Geometry/Soldermask Top")
		(3 "B.Mask" user "Board Geometry/Soldermask Bottom")
		(17 "Dwgs.User" user "User.Drawings")
		(19 "Cmts.User" user "User.Comments")
		(21 "Eco1.User" user "User.Eco1")
		(23 "Eco2.User" user "User.Eco2")
		(25 "Edge.Cuts" user "Board Geometry/Outline")
		(27 "Margin" user)
		(31 "F.CrtYd" user "Package Geometry/Place Bound Top")
		(29 "B.CrtYd" user "Package Geometry/Place Bound Bottom")
		(35 "F.Fab" user "Ref Des/Assembly Top")
		(33 "B.Fab" user "Ref Des/Assembly Bottom")
	)
	(footprint ""
		(layer "B.Cu")
		(at 167.377618 -416.946588 180)
		(property "Reference" "C12"
			(at 0 0 0)
			(layer "B.SilkS")
			(hide yes)
			(effects
				(font
					(size 1.27 1.27)
				)
				(justify mirror)
			)
		)
		(property "Value" ""
			(at 0 0 0)
			(layer "B.Fab")
			(effects
				(font
					(size 1.27 1.27)
				)
				(justify mirror)
			)
		)
		(duplicate_pad_numbers_are_jumpers no)
		(fp_line
			(start 0.7874 0.4064)
			(end 0.7874 -0.4064)
			(stroke
				(width 0.1524)
				(type default)
			)
			(layer "B.SilkS")
		)
		(fp_line
			(start 0.7874 -0.4064)
			(end -0.7874 -0.4064)
			(stroke
				(width 0.1524)
				(type default)
			)
			(layer "B.SilkS")
		)
		(fp_line
			(start -0.7874 0.4064)
			(end 0.7874 0.4064)
			(stroke
				(width 0.1524)
				(type default)
			)
			(layer "B.SilkS")
		)
		(fp_line
			(start -0.7874 -0.4064)
			(end -0.7874 0.4064)
			(stroke
				(width 0.1524)
				(type default)
			)
			(layer "B.SilkS")
		)
		(fp_line
			(start 0.67945 0.3048)
			(end 0.67945 -0.305054)
			(stroke
				(width 0.1)
				(type default)
			)
			(layer "B.Fab")
		)
		(fp_line
			(start 0.67945 -0.305054)
			(end 0.12065 -0.305054)
			(stroke
				(width 0.1)
				(type default)
			)
			(layer "B.Fab")
		)
		(fp_line
			(start 0.12065 0.3048)
			(end 0.67945 0.3048)
			(stroke
				(width 0.1)
				(type default)
			)
			(layer "B.Fab")
		)
		(fp_line
			(start 0.12065 0.2794)
			(end 0.12065 0.3048)
			(stroke
				(width 0.1)
				(type default)
			)
			(layer "B.Fab")
		)
		(fp_line
			(start 0.12065 -0.2794)
			(end -0.12065 -0.2794)
			(stroke
				(width 0.1)
				(type default)
			)
			(layer "B.Fab")
		)
		(fp_line
			(start 0.12065 -0.305054)
			(end 0.12065 -0.2794)
			(stroke
				(width 0.1)
				(type default)
			)
			(layer "B.Fab")
		)
		(fp_line
			(start -0.120396 0.3048)
			(end -0.120396 0.2794)
			(stroke
				(width 0.1)
				(type default)
			)
			(layer "B.Fab")
		)
		(fp_line
			(start -0.120396 0.2794)
			(end 0.12065 0.2794)
			(stroke
				(width 0.1)
				(type default)
			)
			(layer "B.Fab")
		)
		(fp_line
			(start -0.12065 -0.2794)
			(end -0.12065 -0.3048)
			(stroke
				(width 0.1)
				(type default)
			)
			(layer "B.Fab")
		)
		(fp_line
			(start -0.12065 -0.3048)
			(end -0.67945 -0.3048)
			(stroke
				(width 0.1)
				(type default)
			)
			(layer "B.Fab")
		)
		(fp_line
			(start -0.67945 0.3048)
			(end -0.120396 0.3048)
			(stroke
				(width 0.1)
				(type default)
			)
			(layer "B.Fab")
		)
		(fp_line
			(start -0.67945 -0.3048)
			(end -0.67945 0.3048)
			(stroke
				(width 0.1)
				(type default)
			)
			(layer "B.Fab")
		)
		(pad "1" smd circle
			(at 0.40005 0)
			(size 0 0)
			(layers "B.Cu" "B.Mask" "B.Paste")
			(net "GPU_3V3IO_RSVD0_FFU_ISO")
		)
		(pad "2" smd circle
			(at -0.40005 0)
			(size 0 0)
			(layers "B.Cu" "B.Mask" "B.Paste")
			(net "GND")
		)
	)
	(footprint ""
		(layer "B.Cu")
		(at 178.689 -100.294948 -90)
		(property "Reference" "R141"
			(at 0 0 90)
			(layer "B.SilkS")
			(hide yes)
			(effects
				(font
					(size 1.27 1.27)
				)
				(justify mirror)
			)
		)
		(property "Value" ""
			(at 0 0 90)
			(layer "B.Fab")
			(effects
				(font
					(size 1.27 1.27)
				)
				(justify mirror)
			)
		)
		(duplicate_pad_numbers_are_jumpers no)
		(fp_line
			(start -0.7874 0.4064)
			(end 0.7874 0.4064)
			(stroke
				(width 0.1524)
				(type default)
			)
			(layer "B.SilkS")
		)
		(fp_line
			(start 0.7874 0.4064)
			(end 0.7874 -0.4064)
			(stroke
				(width 0.1524)
				(type default)
			)
			(layer "B.SilkS")
		)
		(fp_line
			(start -0.7874 -0.4064)
			(end -0.7874 0.4064)
			(stroke
				(width 0.1524)
				(type default)
			)
			(layer "B.SilkS")
		)
		(fp_line
			(start 0.7874 -0.4064)
			(end -0.7874 -0.4064)
			(stroke
				(width 0.1524)
				(type default)
			)
			(layer "B.SilkS")
		)
		(fp_line
			(start -0.67945 0.3048)
			(end -0.120396 0.3048)
			(stroke
				(width 0.1)
				(type default)
			)
			(layer "B.Fab")
		)
		(fp_line
			(start -0.120396 0.3048)
			(end -0.120396 0.2794)
			(stroke
				(width 0.1)
				(type default)
			)
			(layer "B.Fab")
		)
		(fp_line
			(start 0.12065 0.3048)
			(end 0.67945 0.3048)
			(stroke
				(width 0.1)
				(type default)
			)
			(layer "B.Fab")
		)
		(fp_line
			(start 0.67945 0.3048)
			(end 0.67945 -0.305054)
			(stroke
				(width 0.1)
				(type default)
			)
			(layer "B.Fab")
		)
		(fp_line
			(start -0.120396 0.2794)
			(end 0.12065 0.2794)
			(stroke
				(width 0.1)
				(type default)
			)
			(layer "B.Fab")
		)
		(fp_line
			(start 0.12065 0.2794)
			(end 0.12065 0.3048)
			(stroke
				(width 0.1)
				(type default)
			)
			(layer "B.Fab")
		)
		(fp_line
			(start -0.12065 -0.2794)
			(end -0.12065 -0.3048)
			(stroke
				(width 0.1)
				(type default)
			)
			(layer "B.Fab")
		)
		(fp_line
			(start 0.12065 -0.2794)
			(end -0.12065 -0.2794)
			(stroke
				(width 0.1)
				(type default)
			)
			(layer "B.Fab")
		)
		(fp_line
			(start -0.67945 -0.3048)
			(end -0.67945 0.3048)
			(stroke
				(width 0.1)
				(type default)
			)
			(layer "B.Fab")
		)
		(fp_line
			(start -0.12065 -0.3048)
			(end -0.67945 -0.3048)
			(stroke
				(width 0.1)
				(type default)
			)
			(layer "B.Fab")
		)
		(fp_line
			(start 0.12065 -0.305054)
			(end 0.12065 -0.2794)
			(stroke
				(width 0.1)
				(type default)
			)
			(layer "B.Fab")
		)
		(fp_line
			(start 0.67945 -0.305054)
			(end 0.12065 -0.305054)
			(stroke
				(width 0.1)
				(type default)
			)
			(layer "B.Fab")
		)
		(pad "1" smd circle
			(at 0.40005 0 90)
			(size 0 0)
			(layers "B.Cu" "B.Mask" "B.Paste")
			(net "PVDDCR_CPU1_P1_OCP_N")
		)
		(pad "2" smd circle
			(at -0.40005 0 90)
			(size 0 0)
			(layers "B.Cu" "B.Mask" "B.Paste")
			(net "FM_PVDDCR_CPU1_P1_OCP_N")
		)
	)
)
